(kicad_pcb
	(version 20260206)
	(generator "pcbnew")
	(generator_version "10.0")
	(general
		(thickness 1.6)
		(legacy_teardrops no)
	)
	(paper "A4")
	(title_block
		(title "04192023_DAF0TMB3IC0_F0TG_MB_C_brd_V02_OCP.brd")
		(comment 1 "Grand Teton / footprints 6554-6559 of 8354")
	)
	(layers
		(0 "F.Cu" signal "TOP")
		(4 "In1.Cu" signal "GND")
		(6 "In2.Cu" signal "IN1")
		(8 "In3.Cu" signal "GND1")
		(10 "In4.Cu" signal "IN2")
		(12 "In5.Cu" signal "GND2")
		(14 "In6.Cu" signal "IN3")
		(16 "In7.Cu" signal "GND3")
		(18 "In8.Cu" signal "VCC")
		(20 "In9.Cu" signal "VCC1")
		(22 "In10.Cu" signal "GND4")
		(24 "In11.Cu" signal "IN4")
		(26 "In12.Cu" signal "GND5")
		(28 "In13.Cu" signal "IN5")
		(30 "In14.Cu" signal "GND6")
		(32 "In15.Cu" signal "IN6")
		(34 "In16.Cu" signal "GND7")
		(2 "B.Cu" signal "BOTTOM")
		(9 "F.Adhes" user "F.Adhesive")
		(11 "B.Adhes" user "B.Adhesive")
		(13 "F.Paste" user "Package Geometry/Pastemask Top")
		(15 "B.Paste" user "Package Geometry/Pastemask Bottom")
		(5 "F.SilkS" user "Ref Des/Silkscreen Top")
		(7 "B.SilkS" user "Ref Des/Silkscreen Bottom")
		(1 "F.Mask" user "Board Geometry/Soldermask Top")
		(3 "B.Mask" user "Board Geometry/Soldermask Bottom")
		(17 "Dwgs.User" user "User.Drawings")
		(19 "Cmts.User" user "User.Comments")
		(21 "Eco1.User" user "User.Eco1")
		(23 "Eco2.User" user "User.Eco2")
		(25 "Edge.Cuts" user "Board Geometry/Outline")
		(27 "Margin" user)
		(31 "F.CrtYd" user "Package Geometry/Place Bound Top")
		(29 "B.CrtYd" user "Package Geometry/Place Bound Bottom")
		(35 "F.Fab" user "Ref Des/Assembly Top")
		(33 "B.Fab" user "Ref Des/Assembly Bottom")
	)
	(footprint ""
		(layer "B.Cu")
		(at 501.233948 -298.343066 -90)
		(property "Reference" "X26"
			(at 3.089656 3.232658 270)
			(unlocked yes)
			(layer "B.SilkS")
			(effects
				(font
					(size 0.7874 0.5842)
					(thickness 0.1524)
				)
				(justify left mirror)
			)
		)
		(property "Value" ""
			(at 0 0 90)
			(layer "B.Fab")
			(effects
				(font
					(size 1.27 1.27)
				)
				(justify mirror)
			)
		)
		(property "User Part Number" "N_A"
			(at -1.30175 1.27 180)
			(unlocked yes)
			(layer "Cmts.User")
			(hide yes)
			(effects
				(font
					(size 0.635 0.4064)
					(thickness 0.1524)
				)
				(justify mirror)
			)
		)
		(property "Device Type" "TP_TDR_4P_FTS_TH-TP_TDR_4P_DIP,EMPTY,TP15"
			(at -1.30175 1.27 180)
			(unlocked yes)
			(layer "B.Fab")
			(hide yes)
			(effects
				(font
					(size 0.635 0.4064)
					(thickness 0.1524)
				)
				(justify mirror)
			)
		)
		(duplicate_pad_numbers_are_jumpers no)
		(fp_line
			(start -2.54 3.81)
			(end -2.54 3.6703)
			(stroke
				(width 0.1524)
				(type default)
			)
			(layer "B.SilkS")
		)
		(fp_line
			(start 0 3.81)
			(end -2.54 3.81)
			(stroke
				(width 0.1524)
				(type default)
			)
			(layer "B.SilkS")
		)
		(fp_line
			(start 0 3.175)
			(end 0 3.81)
			(stroke
				(width 0.1524)
				(type default)
			)
			(layer "B.SilkS")
		)
		(fp_line
			(start -2.54 1.4097)
			(end -2.54 1.1303)
			(stroke
				(width 0.1524)
				(type default)
			)
			(layer "B.SilkS")
		)
		(fp_line
			(start 0 0.635)
			(end 0 1.905)
			(stroke
				(width 0.1524)
				(type default)
			)
			(layer "B.SilkS")
		)
		(fp_line
			(start -2.54 -1.1303)
			(end -2.54 -1.27)
			(stroke
				(width 0.1524)
				(type default)
			)
			(layer "B.SilkS")
		)
		(fp_line
			(start -2.54 -1.27)
			(end 0 -1.27)
			(stroke
				(width 0.1524)
				(type default)
			)
			(layer "B.SilkS")
		)
		(fp_line
			(start 0 -1.27)
			(end 0 -0.635)
			(stroke
				(width 0.1524)
				(type default)
			)
			(layer "B.SilkS")
		)
		(fp_poly
			(pts
				(xy 2.285746 -0.762) (xy 2.285746 0.762) (xy 0.761746 0)
			)
			(stroke
				(width 0)
				(type default)
			)
			(fill yes)
			(layer "B.SilkS")
		)
		(fp_line
			(start -2.54 3.81)
			(end -2.54 -1.27)
			(stroke
				(width 0.1)
				(type default)
			)
			(layer "B.Fab")
		)
		(fp_line
			(start 0 3.81)
			(end -2.54 3.81)
			(stroke
				(width 0.1)
				(type default)
			)
			(layer "B.Fab")
		)
		(fp_line
			(start -2.54 -1.27)
			(end 0 -1.27)
			(stroke
				(width 0.1)
				(type default)
			)
			(layer "B.Fab")
		)
		(fp_line
			(start 0 -1.27)
			(end 0 3.81)
			(stroke
				(width 0.1)
				(type default)
			)
			(layer "B.Fab")
		)
		(fp_poly
			(pts
				(xy 0.761746 0) (xy 2.285746 -0.762) (xy 2.285746 0.762)
			)
			(stroke
				(width 0)
				(type default)
			)
			(fill yes)
			(layer "B.Fab")
		)
		(pad "1" thru_hole circle
			(at 0 0 90)
			(size 1.0033 1.0033)
			(drill 0.249936)
			(layers "*.Cu" "*.Mask")
			(remove_unused_layers no)
			(net "TDR_DIFF_80_IN6_DP")
			(clearance 0.10795)
			(padstack
				(mode front_inner_back)
				(layer "Inner"
					(shape circle)
					(size 0.8001 0.8001)
					(clearance 0.1524)
				)
				(layer "B.Cu"
					(shape circle)
					(size 1.0033 1.0033)
					(thermal_gap 0.10795)
					(clearance 0.10795)
				)
			)
		)
		(pad "2" thru_hole circle
			(at -2.54 0 90)
			(size 1.9939 1.9939)
			(drill 0.249936)
			(layers "*.Cu" "*.Mask")
			(remove_unused_layers no)
			(net "T1_GND")
			(clearance 0.10795)
			(padstack
				(mode front_inner_back)
				(layer "Inner"
					(shape circle)
					(size 0.8001 0.8001)
					(clearance 0.1524)
				)
				(layer "B.Cu"
					(shape circle)
					(size 1.9939 1.9939)
					(thermal_gap 0.10795)
					(clearance 0.10795)
				)
			)
		)
		(pad "3" thru_hole circle
			(at -2.54 2.54 90)
			(size 1.9939 1.9939)
			(drill 0.249936)
			(layers "*.Cu" "*.Mask")
			(remove_unused_layers no)
			(net "T1_GND")
			(clearance 0.10795)
			(padstack
				(mode front_inner_back)
				(layer "Inner"
					(shape circle)
					(size 0.8001 0.8001)
					(clearance 0.1524)
				)
				(layer "B.Cu"
					(shape circle)
					(size 1.9939 1.9939)
					(thermal_gap 0.10795)
					(clearance 0.10795)
				)
			)
		)
		(pad "4" thru_hole circle
			(at 0 2.54 90)
			(size 1.0033 1.0033)
			(drill 0.249936)
			(layers "*.Cu" "*.Mask")
			(remove_unused_layers no)
			(net "TDR_DIFF_80_IN6_DN")
			(clearance 0.10795)
			(padstack
				(mode front_inner_back)
				(layer "Inner"
					(shape circle)
					(size 0.8001 0.8001)
					(clearance 0.1524)
				)
				(layer "B.Cu"
					(shape circle)
					(size 1.0033 1.0033)
					(thermal_gap 0.10795)
					(clearance 0.10795)
				)
			)
		)
	)
	(footprint ""
		(layer "B.Cu")
		(at 178.430174 -13.756132 90)
		(property "Reference" "R1384"
			(at 0 0 90)
			(layer "B.SilkS")
			(hide yes)
			(effects
				(font
					(size 1.27 1.27)
				)
				(justify mirror)
			)
		)
		(property "Value" ""
			(at 0 0 90)
			(layer "B.Fab")
			(effects
				(font
					(size 1.27 1.27)
				)
				(justify mirror)
			)
		)
		(duplicate_pad_numbers_are_jumpers no)
		(fp_line
			(start 0.7874 -0.4064)
			(end -0.7874 -0.4064)
			(stroke
				(width 0.1524)
				(type default)
			)
			(layer "B.SilkS")
		)
		(fp_line
			(start -0.7874 -0.4064)
			(end -0.7874 0.4064)
			(stroke
				(width 0.1524)
				(type default)
			)
			(layer "B.SilkS")
		)
		(fp_line
			(start 0.7874 0.4064)
			(end 0.7874 -0.4064)
			(stroke
				(width 0.1524)
				(type default)
			)
			(layer "B.SilkS")
		)
		(fp_line
			(start -0.7874 0.4064)
			(end 0.7874 0.4064)
			(stroke
				(width 0.1524)
				(type default)
			)
			(layer "B.SilkS")
		)
		(fp_line
			(start 0.67945 -0.305054)
			(end 0.12065 -0.305054)
			(stroke
				(width 0.1)
				(type default)
			)
			(layer "B.Fab")
		)
		(fp_line
			(start 0.12065 -0.305054)
			(end 0.12065 -0.2794)
			(stroke
				(width 0.1)
				(type default)
			)
			(layer "B.Fab")
		)
		(fp_line
			(start -0.12065 -0.3048)
			(end -0.67945 -0.3048)
			(stroke
				(width 0.1)
				(type default)
			)
			(layer "B.Fab")
		)
		(fp_line
			(start -0.67945 -0.3048)
			(end -0.67945 0.3048)
			(stroke
				(width 0.1)
				(type default)
			)
			(layer "B.Fab")
		)
		(fp_line
			(start 0.12065 -0.2794)
			(end -0.12065 -0.2794)
			(stroke
				(width 0.1)
				(type default)
			)
			(layer "B.Fab")
		)
		(fp_line
			(start -0.12065 -0.2794)
			(end -0.12065 -0.3048)
			(stroke
				(width 0.1)
				(type default)
			)
			(layer "B.Fab")
		)
		(fp_line
			(start 0.12065 0.2794)
			(end 0.12065 0.3048)
			(stroke
				(width 0.1)
				(type default)
			)
			(layer "B.Fab")
		)
		(fp_line
			(start -0.120396 0.2794)
			(end 0.12065 0.2794)
			(stroke
				(width 0.1)
				(type default)
			)
			(layer "B.Fab")
		)
		(fp_line
			(start 0.67945 0.3048)
			(end 0.67945 -0.305054)
			(stroke
				(width 0.1)
				(type default)
			)
			(layer "B.Fab")
		)
		(fp_line
			(start 0.12065 0.3048)
			(end 0.67945 0.3048)
			(stroke
				(width 0.1)
				(type default)
			)
			(layer "B.Fab")
		)
		(fp_line
			(start -0.120396 0.3048)
			(end -0.120396 0.2794)
			(stroke
				(width 0.1)
				(type default)
			)
			(layer "B.Fab")
		)
		(fp_line
			(start -0.67945 0.3048)
			(end -0.120396 0.3048)
			(stroke
				(width 0.1)
				(type default)
			)
			(layer "B.Fab")
		)
		(pad "1" smd circle
			(at 0.40005 0 270)
			(size 0 0)
			(layers "B.Cu" "B.Mask" "B.Paste")
			(net "SMB_CPU0_CPU1_SEC_SCL")
		)
		(pad "2" smd circle
			(at -0.40005 0 270)
			(size 0 0)
			(layers "B.Cu" "B.Mask" "B.Paste")
			(net "P3V3_AUX")
		)
	)
	(footprint ""
		(layer "B.Cu")
		(at 442.543946 -192.660016 180)
		(property "Reference" "C167"
			(at 0 0 0)
			(layer "B.SilkS")
			(hide yes)
			(effects
				(font
					(size 1.27 1.27)
				)
				(justify mirror)
			)
		)
		(property "Value" ""
			(at 0 0 0)
			(layer "B.Fab")
			(effects
				(font
					(size 1.27 1.27)
				)
				(justify mirror)
			)
		)
		(duplicate_pad_numbers_are_jumpers no)
		(fp_line
			(start 1.524 0.762)
			(end 1.524 -0.762)
			(stroke
				(width 0.1524)
				(type default)
			)
			(layer "B.SilkS")
		)
		(fp_line
			(start 1.524 -0.762)
			(end -1.524 -0.762)
			(stroke
				(width 0.1524)
				(type default)
			)
			(layer "B.SilkS")
		)
		(fp_line
			(start -1.524 0.762)
			(end 1.524 0.762)
			(stroke
				(width 0.1524)
				(type default)
			)
			(layer "B.SilkS")
		)
		(fp_line
			(start -1.524 -0.762)
			(end -1.524 0.762)
			(stroke
				(width 0.1524)
				(type default)
			)
			(layer "B.SilkS")
		)
		(fp_line
			(start 1.1049 0.724916)
			(end -1.1049 0.724916)
			(stroke
				(width 0.1)
				(type default)
			)
			(layer "B.Fab")
		)
		(fp_line
			(start 1.1049 -0.724916)
			(end 1.1049 0.724916)
			(stroke
				(width 0.1)
				(type default)
			)
			(layer "B.Fab")
		)
		(fp_line
			(start -1.1049 0.724916)
			(end -1.1049 -0.724916)
			(stroke
				(width 0.1)
				(type default)
			)
			(layer "B.Fab")
		)
		(fp_line
			(start -1.1049 -0.724916)
			(end 1.1049 -0.724916)
			(stroke
				(width 0.1)
				(type default)
			)
			(layer "B.Fab")
		)
		(pad "1" smd rect
			(at 0.889 0 180)
			(size 1.016 1.27)
			(layers "B.Cu" "B.Mask" "B.Paste")
			(net "P12V_MEM_CPU0")
		)
		(pad "2" smd rect
			(at -0.889 0 180)
			(size 1.016 1.27)
			(layers "B.Cu" "B.Mask" "B.Paste")
			(net "GND")
		)
	)
	(footprint ""
		(layer "B.Cu")
		(at 312.547 -359.918)
		(property "Reference" "PR67"
			(at 0 0 0)
			(layer "B.SilkS")
			(hide yes)
			(effects
				(font
					(size 1.27 1.27)
				)
				(justify mirror)
			)
		)
		(property "Value" ""
			(at 0 0 0)
			(layer "B.Fab")
			(effects
				(font
					(size 1.27 1.27)
				)
				(justify mirror)
			)
		)
		(duplicate_pad_numbers_are_jumpers no)
		(fp_line
			(start -0.7874 -0.4064)
			(end -0.7874 0.4064)
			(stroke
				(width 0.1524)
				(type default)
			)
			(layer "B.SilkS")
		)
		(fp_line
			(start -0.7874 0.4064)
			(end 0.7874 0.4064)
			(stroke
				(width 0.1524)
				(type default)
			)
			(layer "B.SilkS")
		)
		(fp_line
			(start 0.7874 -0.4064)
			(end -0.7874 -0.4064)
			(stroke
				(width 0.1524)
				(type default)
			)
			(layer "B.SilkS")
		)
		(fp_line
			(start 0.7874 0.4064)
			(end 0.7874 -0.4064)
			(stroke
				(width 0.1524)
				(type default)
			)
			(layer "B.SilkS")
		)
		(fp_line
			(start -0.67945 -0.3048)
			(end -0.67945 0.3048)
			(stroke
				(width 0.1)
				(type default)
			)
			(layer "B.Fab")
		)
		(fp_line
			(start -0.67945 0.3048)
			(end -0.120396 0.3048)
			(stroke
				(width 0.1)
				(type default)
			)
			(layer "B.Fab")
		)
		(fp_line
			(start -0.12065 -0.3048)
			(end -0.67945 -0.3048)
			(stroke
				(width 0.1)
				(type default)
			)
			(layer "B.Fab")
		)
		(fp_line
			(start -0.12065 -0.2794)
			(end -0.12065 -0.3048)
			(stroke
				(width 0.1)
				(type default)
			)
			(layer "B.Fab")
		)
		(fp_line
			(start -0.120396 0.2794)
			(end 0.12065 0.2794)
			(stroke
				(width 0.1)
				(type default)
			)
			(layer "B.Fab")
		)
		(fp_line
			(start -0.120396 0.3048)
			(end -0.120396 0.2794)
			(stroke
				(width 0.1)
				(type default)
			)
			(layer "B.Fab")
		)
		(fp_line
			(start 0.12065 -0.305054)
			(end 0.12065 -0.2794)
			(stroke
				(width 0.1)
				(type default)
			)
			(layer "B.Fab")
		)
		(fp_line
			(start 0.12065 -0.2794)
			(end -0.12065 -0.2794)
			(stroke
				(width 0.1)
				(type default)
			)
			(layer "B.Fab")
		)
		(fp_line
			(start 0.12065 0.2794)
			(end 0.12065 0.3048)
			(stroke
				(width 0.1)
				(type default)
			)
			(layer "B.Fab")
		)
		(fp_line
			(start 0.12065 0.3048)
			(end 0.67945 0.3048)
			(stroke
				(width 0.1)
				(type default)
			)
			(layer "B.Fab")
		)
		(fp_line
			(start 0.67945 -0.305054)
			(end 0.12065 -0.305054)
			(stroke
				(width 0.1)
				(type default)
			)
			(layer "B.Fab")
		)
		(fp_line
			(start 0.67945 0.3048)
			(end 0.67945 -0.305054)
			(stroke
				(width 0.1)
				(type default)
			)
			(layer "B.Fab")
		)
		(pad "1" smd circle
			(at 0.40005 0 180)
			(size 0 0)
			(layers "B.Cu" "B.Mask" "B.Paste")
			(net "PVDDCR_CPU1_P0_EN1_ADDR_CFG")
		)
		(pad "2" smd circle
			(at -0.40005 0 180)
			(size 0 0)
			(layers "B.Cu" "B.Mask" "B.Paste")
			(net "GND")
		)
	)
	(footprint ""
		(layer "B.Cu")
		(at 373.018558 -396.393162 -90)
		(property "Reference" "C1011"
			(at 0 0 90)
			(layer "B.SilkS")
			(hide yes)
			(effects
				(font
					(size 1.27 1.27)
				)
				(justify mirror)
			)
		)
		(property "Value" ""
			(at 0 0 90)
			(layer "B.Fab")
			(effects
				(font
					(size 1.27 1.27)
				)
				(justify mirror)
			)
		)
		(duplicate_pad_numbers_are_jumpers no)
		(fp_line
			(start -0.299974 0.150114)
			(end 0.299974 0.150114)
			(stroke
				(width 0.1)
				(type default)
			)
			(layer "B.Fab")
		)
		(fp_line
			(start 0.299974 0.150114)
			(end 0.299974 -0.150114)
			(stroke
				(width 0.1)
				(type default)
			)
			(layer "B.Fab")
		)
		(fp_line
			(start -0.299974 -0.150114)
			(end -0.299974 0.150114)
			(stroke
				(width 0.1)
				(type default)
			)
			(layer "B.Fab")
		)
		(fp_line
			(start 0.299974 -0.150114)
			(end -0.299974 -0.150114)
			(stroke
				(width 0.1)
				(type default)
			)
			(layer "B.Fab")
		)
		(pad "1" smd rect
			(at 0.2667 0 90)
			(size 0.3048 0.381)
			(layers "B.Cu" "B.Mask" "B.Paste")
			(net "P0V9_CPU0_RT3_2A")
		)
		(pad "2" smd rect
			(at -0.2667 0 90)
			(size 0.3048 0.381)
			(layers "B.Cu" "B.Mask" "B.Paste")
			(net "GND")
		)
	)
	(footprint ""
		(layer "B.Cu")
		(at 147.018756 -390.560052 90)
		(property "Reference" "C410"
			(at 0 0 90)
			(layer "B.SilkS")
			(hide yes)
			(effects
				(font
					(size 1.27 1.27)
				)
				(justify mirror)
			)
		)
		(property "Value" ""
			(at 0 0 90)
			(layer "B.Fab")
			(effects
				(font
					(size 1.27 1.27)
				)
				(justify mirror)
			)
		)
		(duplicate_pad_numbers_are_jumpers no)
		(fp_line
			(start 0.7874 -0.4064)
			(end -0.7874 -0.4064)
			(stroke
				(width 0.1524)
				(type default)
			)
			(layer "B.SilkS")
		)
		(fp_line
			(start -0.7874 -0.4064)
			(end -0.7874 0.4064)
			(stroke
				(width 0.1524)
				(type default)
			)
			(layer "B.SilkS")
		)
		(fp_line
			(start 0.7874 0.4064)
			(end 0.7874 -0.4064)
			(stroke
				(width 0.1524)
				(type default)
			)
			(layer "B.SilkS")
		)
		(fp_line
			(start -0.7874 0.4064)
			(end 0.7874 0.4064)
			(stroke
				(width 0.1524)
				(type default)
			)
			(layer "B.SilkS")
		)
		(fp_line
			(start 0.67945 -0.305054)
			(end 0.12065 -0.305054)
			(stroke
				(width 0.1)
				(type default)
			)
			(layer "B.Fab")
		)
		(fp_line
			(start 0.12065 -0.305054)
			(end 0.12065 -0.2794)
			(stroke
				(width 0.1)
				(type default)
			)
			(layer "B.Fab")
		)
		(fp_line
			(start -0.12065 -0.3048)
			(end -0.67945 -0.3048)
			(stroke
				(width 0.1)
				(type default)
			)
			(layer "B.Fab")
		)
		(fp_line
			(start -0.67945 -0.3048)
			(end -0.67945 0.3048)
			(stroke
				(width 0.1)
				(type default)
			)
			(layer "B.Fab")
		)
		(fp_line
			(start 0.12065 -0.2794)
			(end -0.12065 -0.2794)
			(stroke
				(width 0.1)
				(type default)
			)
			(layer "B.Fab")
		)
		(fp_line
			(start -0.12065 -0.2794)
			(end -0.12065 -0.3048)
			(stroke
				(width 0.1)
				(type default)
			)
			(layer "B.Fab")
		)
		(fp_line
			(start 0.12065 0.2794)
			(end 0.12065 0.3048)
			(stroke
				(width 0.1)
				(type default)
			)
			(layer "B.Fab")
		)
		(fp_line
			(start -0.120396 0.2794)
			(end 0.12065 0.2794)
			(stroke
				(width 0.1)
				(type default)
			)
			(layer "B.Fab")
		)
		(fp_line
			(start 0.67945 0.3048)
			(end 0.67945 -0.305054)
			(stroke
				(width 0.1)
				(type default)
			)
			(layer "B.Fab")
		)
		(fp_line
			(start 0.12065 0.3048)
			(end 0.67945 0.3048)
			(stroke
				(width 0.1)
				(type default)
			)
			(layer "B.Fab")
		)
		(fp_line
			(start -0.120396 0.3048)
			(end -0.120396 0.2794)
			(stroke
				(width 0.1)
				(type default)
			)
			(layer "B.Fab")
		)
		(fp_line
			(start -0.67945 0.3048)
			(end -0.120396 0.3048)
			(stroke
				(width 0.1)
				(type default)
			)
			(layer "B.Fab")
		)
		(pad "1" smd circle
			(at 0.40005 0 270)
			(size 0 0)
			(layers "B.Cu" "B.Mask" "B.Paste")
			(net "P0V9_CPU1_RT2_2A")
		)
		(pad "2" smd circle
			(at -0.40005 0 270)
			(size 0 0)
			(layers "B.Cu" "B.Mask" "B.Paste")
			(net "GND")
		)
	)
)
